(kicad_pcb
	(version 20260206)
	(generator "pcbnew")
	(generator_version "10.0")
	(general
		(thickness 1.6)
		(legacy_teardrops no)
	)
	(paper "A4")
	(title_block
		(title "12092022_DA0F0TMDCD0_F0T_Management_Board_D_brd_V3_OCP.brd")
		(comment 1 "Grand Teton / footprints 1233-1238 of 1440")
	)
	(layers
		(0 "F.Cu" signal "TOP")
		(4 "In1.Cu" signal "GND")
		(6 "In2.Cu" signal "IN1")
		(8 "In3.Cu" signal "GND1")
		(10 "In4.Cu" signal "IN2")
		(12 "In5.Cu" signal "VCC")
		(14 "In6.Cu" signal "VCC1")
		(16 "In7.Cu" signal "IN3")
		(18 "In8.Cu" signal "GND2")
		(20 "In9.Cu" signal "IN4")
		(22 "In10.Cu" signal "GND3")
		(2 "B.Cu" signal "BOTTOM")
		(9 "F.Adhes" user "F.Adhesive")
		(11 "B.Adhes" user "B.Adhesive")
		(13 "F.Paste" user "Package Geometry/Pastemask Top")
		(15 "B.Paste" user "Package Geometry/Pastemask Bottom")
		(5 "F.SilkS" user "Ref Des/Silkscreen Top")
		(7 "B.SilkS" user "Ref Des/Silkscreen Bottom")
		(1 "F.Mask" user "Board Geometry/Soldermask Top")
		(3 "B.Mask" user "Board Geometry/Soldermask Bottom")
		(17 "Dwgs.User" user "User.Drawings")
		(19 "Cmts.User" user "User.Comments")
		(21 "Eco1.User" user "User.Eco1")
		(23 "Eco2.User" user "User.Eco2")
		(25 "Edge.Cuts" user "Board Geometry/Outline")
		(27 "Margin" user)
		(31 "F.CrtYd" user "Package Geometry/Place Bound Top")
		(29 "B.CrtYd" user "Package Geometry/Place Bound Bottom")
		(35 "F.Fab" user "Ref Des/Assembly Top")
		(33 "B.Fab" user "Ref Des/Assembly Bottom")
	)
	(footprint ""
		(layer "B.Cu")
		(at 29.972 -102.108 180)
		(property "Reference" "C194"
			(at 0 0 0)
			(layer "B.SilkS")
			(hide yes)
			(effects
				(font
					(size 1.27 1.27)
				)
				(justify mirror)
			)
		)
		(property "Value" ""
			(at 0 0 0)
			(layer "B.Fab")
			(effects
				(font
					(size 1.27 1.27)
				)
				(justify mirror)
			)
		)
		(duplicate_pad_numbers_are_jumpers no)
		(fp_line
			(start 1.2954 0.5842)
			(end 1.2954 -0.5842)
			(stroke
				(width 0.1524)
				(type default)
			)
			(layer "B.SilkS")
		)
		(fp_line
			(start 1.2954 -0.5842)
			(end -1.2954 -0.5842)
			(stroke
				(width 0.1524)
				(type default)
			)
			(layer "B.SilkS")
		)
		(fp_line
			(start 0 -0.5842)
			(end 0 0.5842)
			(stroke
				(width 0.1524)
				(type default)
			)
			(layer "B.SilkS")
		)
		(fp_line
			(start -1.2954 0.5842)
			(end 1.2954 0.5842)
			(stroke
				(width 0.1524)
				(type default)
			)
			(layer "B.SilkS")
		)
		(fp_line
			(start -1.2954 -0.5842)
			(end -1.2954 0.5842)
			(stroke
				(width 0.1524)
				(type default)
			)
			(layer "B.SilkS")
		)
		(fp_line
			(start 1.1938 0.4064)
			(end 1.1938 -0.4064)
			(stroke
				(width 0.1)
				(type default)
			)
			(layer "B.Fab")
		)
		(fp_line
			(start 1.1938 -0.4064)
			(end 0.8636 -0.4064)
			(stroke
				(width 0.1)
				(type default)
			)
			(layer "B.Fab")
		)
		(fp_line
			(start 0.8636 0.4572)
			(end 0.8636 0.4064)
			(stroke
				(width 0.1)
				(type default)
			)
			(layer "B.Fab")
		)
		(fp_line
			(start 0.8636 0.4064)
			(end 1.1938 0.4064)
			(stroke
				(width 0.1)
				(type default)
			)
			(layer "B.Fab")
		)
		(fp_line
			(start 0.8636 -0.4064)
			(end 0.8636 -0.4572)
			(stroke
				(width 0.1)
				(type default)
			)
			(layer "B.Fab")
		)
		(fp_line
			(start 0.8636 -0.4572)
			(end -0.8636 -0.4572)
			(stroke
				(width 0.1)
				(type default)
			)
			(layer "B.Fab")
		)
		(fp_line
			(start -0.8636 0.4572)
			(end 0.8636 0.4572)
			(stroke
				(width 0.1)
				(type default)
			)
			(layer "B.Fab")
		)
		(fp_line
			(start -0.8636 0.4064)
			(end -0.8636 0.4572)
			(stroke
				(width 0.1)
				(type default)
			)
			(layer "B.Fab")
		)
		(fp_line
			(start -0.8636 -0.4064)
			(end -1.1938 -0.4064)
			(stroke
				(width 0.1)
				(type default)
			)
			(layer "B.Fab")
		)
		(fp_line
			(start -0.8636 -0.4572)
			(end -0.8636 -0.4064)
			(stroke
				(width 0.1)
				(type default)
			)
			(layer "B.Fab")
		)
		(fp_line
			(start -1.1938 0.4064)
			(end -0.8636 0.4064)
			(stroke
				(width 0.1)
				(type default)
			)
			(layer "B.Fab")
		)
		(fp_line
			(start -1.1938 -0.4064)
			(end -1.1938 0.4064)
			(stroke
				(width 0.1)
				(type default)
			)
			(layer "B.Fab")
		)
		(pad "1" smd rect
			(at 0.7366 0 90)
			(size 0.7112 0.8128)
			(layers "B.Cu" "B.Mask" "B.Paste")
			(net "P3V3_AUX")
		)
		(pad "2" smd rect
			(at -0.7366 0 90)
			(size 0.7112 0.8128)
			(layers "B.Cu" "B.Mask" "B.Paste")
			(net "GND")
		)
	)
	(footprint ""
		(layer "B.Cu")
		(at 80.547464 -51.0413 -90)
		(property "Reference" "R6"
			(at 0 0 90)
			(layer "B.SilkS")
			(hide yes)
			(effects
				(font
					(size 1.27 1.27)
				)
				(justify mirror)
			)
		)
		(property "Value" ""
			(at 0 0 90)
			(layer "B.Fab")
			(effects
				(font
					(size 1.27 1.27)
				)
				(justify mirror)
			)
		)
		(duplicate_pad_numbers_are_jumpers no)
		(fp_line
			(start -0.7874 0.4064)
			(end 0.7874 0.4064)
			(stroke
				(width 0.1524)
				(type default)
			)
			(layer "B.SilkS")
		)
		(fp_line
			(start 0.7874 0.4064)
			(end 0.7874 -0.4064)
			(stroke
				(width 0.1524)
				(type default)
			)
			(layer "B.SilkS")
		)
		(fp_line
			(start -0.7874 -0.4064)
			(end -0.7874 0.4064)
			(stroke
				(width 0.1524)
				(type default)
			)
			(layer "B.SilkS")
		)
		(fp_line
			(start 0.7874 -0.4064)
			(end -0.7874 -0.4064)
			(stroke
				(width 0.1524)
				(type default)
			)
			(layer "B.SilkS")
		)
		(fp_line
			(start -0.67945 0.3048)
			(end -0.120396 0.3048)
			(stroke
				(width 0.1)
				(type default)
			)
			(layer "B.Fab")
		)
		(fp_line
			(start -0.120396 0.3048)
			(end -0.120396 0.2794)
			(stroke
				(width 0.1)
				(type default)
			)
			(layer "B.Fab")
		)
		(fp_line
			(start 0.12065 0.3048)
			(end 0.67945 0.3048)
			(stroke
				(width 0.1)
				(type default)
			)
			(layer "B.Fab")
		)
		(fp_line
			(start 0.67945 0.3048)
			(end 0.67945 -0.305054)
			(stroke
				(width 0.1)
				(type default)
			)
			(layer "B.Fab")
		)
		(fp_line
			(start -0.120396 0.2794)
			(end 0.12065 0.2794)
			(stroke
				(width 0.1)
				(type default)
			)
			(layer "B.Fab")
		)
		(fp_line
			(start 0.12065 0.2794)
			(end 0.12065 0.3048)
			(stroke
				(width 0.1)
				(type default)
			)
			(layer "B.Fab")
		)
		(fp_line
			(start -0.12065 -0.2794)
			(end -0.12065 -0.3048)
			(stroke
				(width 0.1)
				(type default)
			)
			(layer "B.Fab")
		)
		(fp_line
			(start 0.12065 -0.2794)
			(end -0.12065 -0.2794)
			(stroke
				(width 0.1)
				(type default)
			)
			(layer "B.Fab")
		)
		(fp_line
			(start -0.67945 -0.3048)
			(end -0.67945 0.3048)
			(stroke
				(width 0.1)
				(type default)
			)
			(layer "B.Fab")
		)
		(fp_line
			(start -0.12065 -0.3048)
			(end -0.67945 -0.3048)
			(stroke
				(width 0.1)
				(type default)
			)
			(layer "B.Fab")
		)
		(fp_line
			(start 0.12065 -0.305054)
			(end 0.12065 -0.2794)
			(stroke
				(width 0.1)
				(type default)
			)
			(layer "B.Fab")
		)
		(fp_line
			(start 0.67945 -0.305054)
			(end 0.12065 -0.305054)
			(stroke
				(width 0.1)
				(type default)
			)
			(layer "B.Fab")
		)
		(pad "1" smd circle
			(at 0.40005 0 90)
			(size 0 0)
			(layers "B.Cu" "B.Mask" "B.Paste")
			(net "PD_M_BMC_DDR4_ZQ")
		)
		(pad "2" smd circle
			(at -0.40005 0 90)
			(size 0 0)
			(layers "B.Cu" "B.Mask" "B.Paste")
			(net "GND")
		)
	)
	(footprint ""
		(layer "B.Cu")
		(at 49.657 -30.861 -90)
		(property "Reference" "R265"
			(at 0 0 90)
			(layer "B.SilkS")
			(hide yes)
			(effects
				(font
					(size 1.27 1.27)
				)
				(justify mirror)
			)
		)
		(property "Value" ""
			(at 0 0 90)
			(layer "B.Fab")
			(effects
				(font
					(size 1.27 1.27)
				)
				(justify mirror)
			)
		)
		(duplicate_pad_numbers_are_jumpers no)
		(fp_line
			(start -0.7874 0.4064)
			(end 0.7874 0.4064)
			(stroke
				(width 0.1524)
				(type default)
			)
			(layer "B.SilkS")
		)
		(fp_line
			(start 0.7874 0.4064)
			(end 0.7874 -0.4064)
			(stroke
				(width 0.1524)
				(type default)
			)
			(layer "B.SilkS")
		)
		(fp_line
			(start -0.7874 -0.4064)
			(end -0.7874 0.4064)
			(stroke
				(width 0.1524)
				(type default)
			)
			(layer "B.SilkS")
		)
		(fp_line
			(start 0.7874 -0.4064)
			(end -0.7874 -0.4064)
			(stroke
				(width 0.1524)
				(type default)
			)
			(layer "B.SilkS")
		)
		(fp_line
			(start -0.67945 0.3048)
			(end -0.120396 0.3048)
			(stroke
				(width 0.1)
				(type default)
			)
			(layer "B.Fab")
		)
		(fp_line
			(start -0.120396 0.3048)
			(end -0.120396 0.2794)
			(stroke
				(width 0.1)
				(type default)
			)
			(layer "B.Fab")
		)
		(fp_line
			(start 0.12065 0.3048)
			(end 0.67945 0.3048)
			(stroke
				(width 0.1)
				(type default)
			)
			(layer "B.Fab")
		)
		(fp_line
			(start 0.67945 0.3048)
			(end 0.67945 -0.305054)
			(stroke
				(width 0.1)
				(type default)
			)
			(layer "B.Fab")
		)
		(fp_line
			(start -0.120396 0.2794)
			(end 0.12065 0.2794)
			(stroke
				(width 0.1)
				(type default)
			)
			(layer "B.Fab")
		)
		(fp_line
			(start 0.12065 0.2794)
			(end 0.12065 0.3048)
			(stroke
				(width 0.1)
				(type default)
			)
			(layer "B.Fab")
		)
		(fp_line
			(start -0.12065 -0.2794)
			(end -0.12065 -0.3048)
			(stroke
				(width 0.1)
				(type default)
			)
			(layer "B.Fab")
		)
		(fp_line
			(start 0.12065 -0.2794)
			(end -0.12065 -0.2794)
			(stroke
				(width 0.1)
				(type default)
			)
			(layer "B.Fab")
		)
		(fp_line
			(start -0.67945 -0.3048)
			(end -0.67945 0.3048)
			(stroke
				(width 0.1)
				(type default)
			)
			(layer "B.Fab")
		)
		(fp_line
			(start -0.12065 -0.3048)
			(end -0.67945 -0.3048)
			(stroke
				(width 0.1)
				(type default)
			)
			(layer "B.Fab")
		)
		(fp_line
			(start 0.12065 -0.305054)
			(end 0.12065 -0.2794)
			(stroke
				(width 0.1)
				(type default)
			)
			(layer "B.Fab")
		)
		(fp_line
			(start 0.67945 -0.305054)
			(end 0.12065 -0.305054)
			(stroke
				(width 0.1)
				(type default)
			)
			(layer "B.Fab")
		)
		(pad "1" smd circle
			(at 0.40005 0 90)
			(size 0 0)
			(layers "B.Cu" "B.Mask" "B.Paste")
			(net "P3V3_AUX")
		)
		(pad "2" smd circle
			(at -0.40005 0 90)
			(size 0 0)
			(layers "B.Cu" "B.Mask" "B.Paste")
			(net "SMB_BMC_MM16_SDA")
		)
	)
	(footprint ""
		(layer "B.Cu")
		(at 64.662304 -51.586638)
		(property "Reference" "R127"
			(at 0 0 0)
			(layer "B.SilkS")
			(hide yes)
			(effects
				(font
					(size 1.27 1.27)
				)
				(justify mirror)
			)
		)
		(property "Value" ""
			(at 0 0 0)
			(layer "B.Fab")
			(effects
				(font
					(size 1.27 1.27)
				)
				(justify mirror)
			)
		)
		(duplicate_pad_numbers_are_jumpers no)
		(fp_line
			(start -0.7874 -0.4064)
			(end -0.7874 0.4064)
			(stroke
				(width 0.1524)
				(type default)
			)
			(layer "B.SilkS")
		)
		(fp_line
			(start -0.7874 0.4064)
			(end 0.7874 0.4064)
			(stroke
				(width 0.1524)
				(type default)
			)
			(layer "B.SilkS")
		)
		(fp_line
			(start 0.7874 -0.4064)
			(end -0.7874 -0.4064)
			(stroke
				(width 0.1524)
				(type default)
			)
			(layer "B.SilkS")
		)
		(fp_line
			(start 0.7874 0.4064)
			(end 0.7874 -0.4064)
			(stroke
				(width 0.1524)
				(type default)
			)
			(layer "B.SilkS")
		)
		(fp_line
			(start -0.67945 -0.3048)
			(end -0.67945 0.3048)
			(stroke
				(width 0.1)
				(type default)
			)
			(layer "B.Fab")
		)
		(fp_line
			(start -0.67945 0.3048)
			(end -0.120396 0.3048)
			(stroke
				(width 0.1)
				(type default)
			)
			(layer "B.Fab")
		)
		(fp_line
			(start -0.12065 -0.3048)
			(end -0.67945 -0.3048)
			(stroke
				(width 0.1)
				(type default)
			)
			(layer "B.Fab")
		)
		(fp_line
			(start -0.12065 -0.2794)
			(end -0.12065 -0.3048)
			(stroke
				(width 0.1)
				(type default)
			)
			(layer "B.Fab")
		)
		(fp_line
			(start -0.120396 0.2794)
			(end 0.12065 0.2794)
			(stroke
				(width 0.1)
				(type default)
			)
			(layer "B.Fab")
		)
		(fp_line
			(start -0.120396 0.3048)
			(end -0.120396 0.2794)
			(stroke
				(width 0.1)
				(type default)
			)
			(layer "B.Fab")
		)
		(fp_line
			(start 0.12065 -0.305054)
			(end 0.12065 -0.2794)
			(stroke
				(width 0.1)
				(type default)
			)
			(layer "B.Fab")
		)
		(fp_line
			(start 0.12065 -0.2794)
			(end -0.12065 -0.2794)
			(stroke
				(width 0.1)
				(type default)
			)
			(layer "B.Fab")
		)
		(fp_line
			(start 0.12065 0.2794)
			(end 0.12065 0.3048)
			(stroke
				(width 0.1)
				(type default)
			)
			(layer "B.Fab")
		)
		(fp_line
			(start 0.12065 0.3048)
			(end 0.67945 0.3048)
			(stroke
				(width 0.1)
				(type default)
			)
			(layer "B.Fab")
		)
		(fp_line
			(start 0.67945 -0.305054)
			(end 0.12065 -0.305054)
			(stroke
				(width 0.1)
				(type default)
			)
			(layer "B.Fab")
		)
		(fp_line
			(start 0.67945 0.3048)
			(end 0.67945 -0.305054)
			(stroke
				(width 0.1)
				(type default)
			)
			(layer "B.Fab")
		)
		(pad "1" smd circle
			(at 0.40005 0 180)
			(size 0 0)
			(layers "B.Cu" "B.Mask" "B.Paste")
			(net "GND")
		)
		(pad "2" smd circle
			(at -0.40005 0 180)
			(size 0 0)
			(layers "B.Cu" "B.Mask" "B.Paste")
			(net "IBMC_MIOZ")
		)
	)
	(footprint ""
		(layer "B.Cu")
		(at 59.551316 -49.314354)
		(property "Reference" "C86"
			(at 0 0 0)
			(layer "B.SilkS")
			(hide yes)
			(effects
				(font
					(size 1.27 1.27)
				)
				(justify mirror)
			)
		)
		(property "Value" ""
			(at 0 0 0)
			(layer "B.Fab")
			(effects
				(font
					(size 1.27 1.27)
				)
				(justify mirror)
			)
		)
		(duplicate_pad_numbers_are_jumpers no)
		(fp_line
			(start -0.7874 -0.4064)
			(end -0.7874 0.4064)
			(stroke
				(width 0.1524)
				(type default)
			)
			(layer "B.SilkS")
		)
		(fp_line
			(start -0.7874 0.4064)
			(end 0.7874 0.4064)
			(stroke
				(width 0.1524)
				(type default)
			)
			(layer "B.SilkS")
		)
		(fp_line
			(start 0.7874 -0.4064)
			(end -0.7874 -0.4064)
			(stroke
				(width 0.1524)
				(type default)
			)
			(layer "B.SilkS")
		)
		(fp_line
			(start 0.7874 0.4064)
			(end 0.7874 -0.4064)
			(stroke
				(width 0.1524)
				(type default)
			)
			(layer "B.SilkS")
		)
		(fp_line
			(start -0.67945 -0.3048)
			(end -0.67945 0.3048)
			(stroke
				(width 0.1)
				(type default)
			)
			(layer "B.Fab")
		)
		(fp_line
			(start -0.67945 0.3048)
			(end -0.120396 0.3048)
			(stroke
				(width 0.1)
				(type default)
			)
			(layer "B.Fab")
		)
		(fp_line
			(start -0.12065 -0.3048)
			(end -0.67945 -0.3048)
			(stroke
				(width 0.1)
				(type default)
			)
			(layer "B.Fab")
		)
		(fp_line
			(start -0.12065 -0.2794)
			(end -0.12065 -0.3048)
			(stroke
				(width 0.1)
				(type default)
			)
			(layer "B.Fab")
		)
		(fp_line
			(start -0.120396 0.2794)
			(end 0.12065 0.2794)
			(stroke
				(width 0.1)
				(type default)
			)
			(layer "B.Fab")
		)
		(fp_line
			(start -0.120396 0.3048)
			(end -0.120396 0.2794)
			(stroke
				(width 0.1)
				(type default)
			)
			(layer "B.Fab")
		)
		(fp_line
			(start 0.12065 -0.305054)
			(end 0.12065 -0.2794)
			(stroke
				(width 0.1)
				(type default)
			)
			(layer "B.Fab")
		)
		(fp_line
			(start 0.12065 -0.2794)
			(end -0.12065 -0.2794)
			(stroke
				(width 0.1)
				(type default)
			)
			(layer "B.Fab")
		)
		(fp_line
			(start 0.12065 0.2794)
			(end 0.12065 0.3048)
			(stroke
				(width 0.1)
				(type default)
			)
			(layer "B.Fab")
		)
		(fp_line
			(start 0.12065 0.3048)
			(end 0.67945 0.3048)
			(stroke
				(width 0.1)
				(type default)
			)
			(layer "B.Fab")
		)
		(fp_line
			(start 0.67945 -0.305054)
			(end 0.12065 -0.305054)
			(stroke
				(width 0.1)
				(type default)
			)
			(layer "B.Fab")
		)
		(fp_line
			(start 0.67945 0.3048)
			(end 0.67945 -0.305054)
			(stroke
				(width 0.1)
				(type default)
			)
			(layer "B.Fab")
		)
		(pad "1" smd circle
			(at 0.40005 0 180)
			(size 0 0)
			(layers "B.Cu" "B.Mask" "B.Paste")
			(net "P1V0_AUX")
		)
		(pad "2" smd circle
			(at -0.40005 0 180)
			(size 0 0)
			(layers "B.Cu" "B.Mask" "B.Paste")
			(net "GND")
		)
	)
	(footprint ""
		(layer "B.Cu")
		(at 83.283552 -28.627578 180)
		(property "Reference" "R411"
			(at 0 0 0)
			(layer "B.SilkS")
			(hide yes)
			(effects
				(font
					(size 1.27 1.27)
				)
				(justify mirror)
			)
		)
		(property "Value" ""
			(at 0 0 0)
			(layer "B.Fab")
			(effects
				(font
					(size 1.27 1.27)
				)
				(justify mirror)
			)
		)
		(duplicate_pad_numbers_are_jumpers no)
		(fp_line
			(start 0.7874 0.4064)
			(end 0.7874 -0.4064)
			(stroke
				(width 0.1524)
				(type default)
			)
			(layer "B.SilkS")
		)
		(fp_line
			(start 0.7874 -0.4064)
			(end -0.7874 -0.4064)
			(stroke
				(width 0.1524)
				(type default)
			)
			(layer "B.SilkS")
		)
		(fp_line
			(start -0.7874 0.4064)
			(end 0.7874 0.4064)
			(stroke
				(width 0.1524)
				(type default)
			)
			(layer "B.SilkS")
		)
		(fp_line
			(start -0.7874 -0.4064)
			(end -0.7874 0.4064)
			(stroke
				(width 0.1524)
				(type default)
			)
			(layer "B.SilkS")
		)
		(fp_line
			(start 0.67945 0.3048)
			(end 0.67945 -0.305054)
			(stroke
				(width 0.1)
				(type default)
			)
			(layer "B.Fab")
		)
		(fp_line
			(start 0.67945 -0.305054)
			(end 0.12065 -0.305054)
			(stroke
				(width 0.1)
				(type default)
			)
			(layer "B.Fab")
		)
		(fp_line
			(start 0.12065 0.3048)
			(end 0.67945 0.3048)
			(stroke
				(width 0.1)
				(type default)
			)
			(layer "B.Fab")
		)
		(fp_line
			(start 0.12065 0.2794)
			(end 0.12065 0.3048)
			(stroke
				(width 0.1)
				(type default)
			)
			(layer "B.Fab")
		)
		(fp_line
			(start 0.12065 -0.2794)
			(end -0.12065 -0.2794)
			(stroke
				(width 0.1)
				(type default)
			)
			(layer "B.Fab")
		)
		(fp_line
			(start 0.12065 -0.305054)
			(end 0.12065 -0.2794)
			(stroke
				(width 0.1)
				(type default)
			)
			(layer "B.Fab")
		)
		(fp_line
			(start -0.120396 0.3048)
			(end -0.120396 0.2794)
			(stroke
				(width 0.1)
				(type default)
			)
			(layer "B.Fab")
		)
		(fp_line
			(start -0.120396 0.2794)
			(end 0.12065 0.2794)
			(stroke
				(width 0.1)
				(type default)
			)
			(layer "B.Fab")
		)
		(fp_line
			(start -0.12065 -0.2794)
			(end -0.12065 -0.3048)
			(stroke
				(width 0.1)
				(type default)
			)
			(layer "B.Fab")
		)
		(fp_line
			(start -0.12065 -0.3048)
			(end -0.67945 -0.3048)
			(stroke
				(width 0.1)
				(type default)
			)
			(layer "B.Fab")
		)
		(fp_line
			(start -0.67945 0.3048)
			(end -0.120396 0.3048)
			(stroke
				(width 0.1)
				(type default)
			)
			(layer "B.Fab")
		)
		(fp_line
			(start -0.67945 -0.3048)
			(end -0.67945 0.3048)
			(stroke
				(width 0.1)
				(type default)
			)
			(layer "B.Fab")
		)
		(pad "1" smd circle
			(at 0.40005 0)
			(size 0 0)
			(layers "B.Cu" "B.Mask" "B.Paste")
			(net "FRU_E0")
		)
		(pad "2" smd circle
			(at -0.40005 0)
			(size 0 0)
			(layers "B.Cu" "B.Mask" "B.Paste")
			(net "GND")
		)
	)
)
